(kicad_pcb
	(version 20260206)
	(generator "pcbnew")
	(generator_version "10.0")
	(general
		(thickness 1.6)
		(legacy_teardrops no)
	)
	(paper "A4")
	(title_block
		(title "04192023_DAF0TMB3IC0_F0TG_MB_C_brd_V02_OCP.brd")
		(comment 1 "Grand Teton / footprints 5779-5784 of 8354")
	)
	(layers
		(0 "F.Cu" signal "TOP")
		(4 "In1.Cu" signal "GND")
		(6 "In2.Cu" signal "IN1")
		(8 "In3.Cu" signal "GND1")
		(10 "In4.Cu" signal "IN2")
		(12 "In5.Cu" signal "GND2")
		(14 "In6.Cu" signal "IN3")
		(16 "In7.Cu" signal "GND3")
		(18 "In8.Cu" signal "VCC")
		(20 "In9.Cu" signal "VCC1")
		(22 "In10.Cu" signal "GND4")
		(24 "In11.Cu" signal "IN4")
		(26 "In12.Cu" signal "GND5")
		(28 "In13.Cu" signal "IN5")
		(30 "In14.Cu" signal "GND6")
		(32 "In15.Cu" signal "IN6")
		(34 "In16.Cu" signal "GND7")
		(2 "B.Cu" signal "BOTTOM")
		(9 "F.Adhes" user "F.Adhesive")
		(11 "B.Adhes" user "B.Adhesive")
		(13 "F.Paste" user "Package Geometry/Pastemask Top")
		(15 "B.Paste" user "Package Geometry/Pastemask Bottom")
		(5 "F.SilkS" user "Ref Des/Silkscreen Top")
		(7 "B.SilkS" user "Ref Des/Silkscreen Bottom")
		(1 "F.Mask" user "Board Geometry/Soldermask Top")
		(3 "B.Mask" user "Board Geometry/Soldermask Bottom")
		(17 "Dwgs.User" user "User.Drawings")
		(19 "Cmts.User" user "User.Comments")
		(21 "Eco1.User" user "User.Eco1")
		(23 "Eco2.User" user "User.Eco2")
		(25 "Edge.Cuts" user "Board Geometry/Outline")
		(27 "Margin" user)
		(31 "F.CrtYd" user "Package Geometry/Place Bound Top")
		(29 "B.CrtYd" user "Package Geometry/Place Bound Bottom")
		(35 "F.Fab" user "Ref Des/Assembly Top")
		(33 "B.Fab" user "Ref Des/Assembly Bottom")
	)
	(footprint ""
		(layer "B.Cu")
		(at 308.191154 -398.942052 90)
		(property "Reference" "C568"
			(at 0 0 90)
			(layer "B.SilkS")
			(hide yes)
			(effects
				(font
					(size 1.27 1.27)
				)
				(justify mirror)
			)
		)
		(property "Value" ""
			(at 0 0 90)
			(layer "B.Fab")
			(effects
				(font
					(size 1.27 1.27)
				)
				(justify mirror)
			)
		)
		(duplicate_pad_numbers_are_jumpers no)
		(fp_line
			(start 0.7874 -0.4064)
			(end -0.7874 -0.4064)
			(stroke
				(width 0.1524)
				(type default)
			)
			(layer "B.SilkS")
		)
		(fp_line
			(start -0.7874 -0.4064)
			(end -0.7874 0.4064)
			(stroke
				(width 0.1524)
				(type default)
			)
			(layer "B.SilkS")
		)
		(fp_line
			(start 0.7874 0.4064)
			(end 0.7874 -0.4064)
			(stroke
				(width 0.1524)
				(type default)
			)
			(layer "B.SilkS")
		)
		(fp_line
			(start -0.7874 0.4064)
			(end 0.7874 0.4064)
			(stroke
				(width 0.1524)
				(type default)
			)
			(layer "B.SilkS")
		)
		(fp_line
			(start 0.67945 -0.305054)
			(end 0.12065 -0.305054)
			(stroke
				(width 0.1)
				(type default)
			)
			(layer "B.Fab")
		)
		(fp_line
			(start 0.12065 -0.305054)
			(end 0.12065 -0.2794)
			(stroke
				(width 0.1)
				(type default)
			)
			(layer "B.Fab")
		)
		(fp_line
			(start -0.12065 -0.3048)
			(end -0.67945 -0.3048)
			(stroke
				(width 0.1)
				(type default)
			)
			(layer "B.Fab")
		)
		(fp_line
			(start -0.67945 -0.3048)
			(end -0.67945 0.3048)
			(stroke
				(width 0.1)
				(type default)
			)
			(layer "B.Fab")
		)
		(fp_line
			(start 0.12065 -0.2794)
			(end -0.12065 -0.2794)
			(stroke
				(width 0.1)
				(type default)
			)
			(layer "B.Fab")
		)
		(fp_line
			(start -0.12065 -0.2794)
			(end -0.12065 -0.3048)
			(stroke
				(width 0.1)
				(type default)
			)
			(layer "B.Fab")
		)
		(fp_line
			(start 0.12065 0.2794)
			(end 0.12065 0.3048)
			(stroke
				(width 0.1)
				(type default)
			)
			(layer "B.Fab")
		)
		(fp_line
			(start -0.120396 0.2794)
			(end 0.12065 0.2794)
			(stroke
				(width 0.1)
				(type default)
			)
			(layer "B.Fab")
		)
		(fp_line
			(start 0.67945 0.3048)
			(end 0.67945 -0.305054)
			(stroke
				(width 0.1)
				(type default)
			)
			(layer "B.Fab")
		)
		(fp_line
			(start 0.12065 0.3048)
			(end 0.67945 0.3048)
			(stroke
				(width 0.1)
				(type default)
			)
			(layer "B.Fab")
		)
		(fp_line
			(start -0.120396 0.3048)
			(end -0.120396 0.2794)
			(stroke
				(width 0.1)
				(type default)
			)
			(layer "B.Fab")
		)
		(fp_line
			(start -0.67945 0.3048)
			(end -0.120396 0.3048)
			(stroke
				(width 0.1)
				(type default)
			)
			(layer "B.Fab")
		)
		(pad "1" smd circle
			(at 0.40005 0 270)
			(size 0 0)
			(layers "B.Cu" "B.Mask" "B.Paste")
			(net "P0V9_CPU0_RT0_2A")
		)
		(pad "2" smd circle
			(at -0.40005 0 270)
			(size 0 0)
			(layers "B.Cu" "B.Mask" "B.Paste")
			(net "GND")
		)
	)
	(footprint ""
		(layer "B.Cu")
		(at 381.291338 -398.942052 90)
		(property "Reference" "C1032"
			(at 0 0 90)
			(layer "B.SilkS")
			(hide yes)
			(effects
				(font
					(size 1.27 1.27)
				)
				(justify mirror)
			)
		)
		(property "Value" ""
			(at 0 0 90)
			(layer "B.Fab")
			(effects
				(font
					(size 1.27 1.27)
				)
				(justify mirror)
			)
		)
		(duplicate_pad_numbers_are_jumpers no)
		(fp_line
			(start 0.7874 -0.4064)
			(end -0.7874 -0.4064)
			(stroke
				(width 0.1524)
				(type default)
			)
			(layer "B.SilkS")
		)
		(fp_line
			(start -0.7874 -0.4064)
			(end -0.7874 0.4064)
			(stroke
				(width 0.1524)
				(type default)
			)
			(layer "B.SilkS")
		)
		(fp_line
			(start 0.7874 0.4064)
			(end 0.7874 -0.4064)
			(stroke
				(width 0.1524)
				(type default)
			)
			(layer "B.SilkS")
		)
		(fp_line
			(start -0.7874 0.4064)
			(end 0.7874 0.4064)
			(stroke
				(width 0.1524)
				(type default)
			)
			(layer "B.SilkS")
		)
		(fp_line
			(start 0.67945 -0.305054)
			(end 0.12065 -0.305054)
			(stroke
				(width 0.1)
				(type default)
			)
			(layer "B.Fab")
		)
		(fp_line
			(start 0.12065 -0.305054)
			(end 0.12065 -0.2794)
			(stroke
				(width 0.1)
				(type default)
			)
			(layer "B.Fab")
		)
		(fp_line
			(start -0.12065 -0.3048)
			(end -0.67945 -0.3048)
			(stroke
				(width 0.1)
				(type default)
			)
			(layer "B.Fab")
		)
		(fp_line
			(start -0.67945 -0.3048)
			(end -0.67945 0.3048)
			(stroke
				(width 0.1)
				(type default)
			)
			(layer "B.Fab")
		)
		(fp_line
			(start 0.12065 -0.2794)
			(end -0.12065 -0.2794)
			(stroke
				(width 0.1)
				(type default)
			)
			(layer "B.Fab")
		)
		(fp_line
			(start -0.12065 -0.2794)
			(end -0.12065 -0.3048)
			(stroke
				(width 0.1)
				(type default)
			)
			(layer "B.Fab")
		)
		(fp_line
			(start 0.12065 0.2794)
			(end 0.12065 0.3048)
			(stroke
				(width 0.1)
				(type default)
			)
			(layer "B.Fab")
		)
		(fp_line
			(start -0.120396 0.2794)
			(end 0.12065 0.2794)
			(stroke
				(width 0.1)
				(type default)
			)
			(layer "B.Fab")
		)
		(fp_line
			(start 0.67945 0.3048)
			(end 0.67945 -0.305054)
			(stroke
				(width 0.1)
				(type default)
			)
			(layer "B.Fab")
		)
		(fp_line
			(start 0.12065 0.3048)
			(end 0.67945 0.3048)
			(stroke
				(width 0.1)
				(type default)
			)
			(layer "B.Fab")
		)
		(fp_line
			(start -0.120396 0.3048)
			(end -0.120396 0.2794)
			(stroke
				(width 0.1)
				(type default)
			)
			(layer "B.Fab")
		)
		(fp_line
			(start -0.67945 0.3048)
			(end -0.120396 0.3048)
			(stroke
				(width 0.1)
				(type default)
			)
			(layer "B.Fab")
		)
		(pad "1" smd circle
			(at 0.40005 0 270)
			(size 0 0)
			(layers "B.Cu" "B.Mask" "B.Paste")
			(net "P0V9_CPU0_RT_2D")
		)
		(pad "2" smd circle
			(at -0.40005 0 270)
			(size 0 0)
			(layers "B.Cu" "B.Mask" "B.Paste")
			(net "GND")
		)
	)
	(footprint ""
		(layer "B.Cu")
		(at 449.443602 -422.01211 180)
		(property "Reference" "PR6814"
			(at 0 0 0)
			(layer "B.SilkS")
			(hide yes)
			(effects
				(font
					(size 1.27 1.27)
				)
				(justify mirror)
			)
		)
		(property "Value" ""
			(at 0 0 0)
			(layer "B.Fab")
			(effects
				(font
					(size 1.27 1.27)
				)
				(justify mirror)
			)
		)
		(duplicate_pad_numbers_are_jumpers no)
		(fp_line
			(start 0.7874 0.4064)
			(end 0.7874 -0.4064)
			(stroke
				(width 0.1524)
				(type default)
			)
			(layer "B.SilkS")
		)
		(fp_line
			(start 0.7874 -0.4064)
			(end -0.7874 -0.4064)
			(stroke
				(width 0.1524)
				(type default)
			)
			(layer "B.SilkS")
		)
		(fp_line
			(start -0.7874 0.4064)
			(end 0.7874 0.4064)
			(stroke
				(width 0.1524)
				(type default)
			)
			(layer "B.SilkS")
		)
		(fp_line
			(start -0.7874 -0.4064)
			(end -0.7874 0.4064)
			(stroke
				(width 0.1524)
				(type default)
			)
			(layer "B.SilkS")
		)
		(fp_line
			(start 0.67945 0.3048)
			(end 0.67945 -0.305054)
			(stroke
				(width 0.1)
				(type default)
			)
			(layer "B.Fab")
		)
		(fp_line
			(start 0.67945 -0.305054)
			(end 0.12065 -0.305054)
			(stroke
				(width 0.1)
				(type default)
			)
			(layer "B.Fab")
		)
		(fp_line
			(start 0.12065 0.3048)
			(end 0.67945 0.3048)
			(stroke
				(width 0.1)
				(type default)
			)
			(layer "B.Fab")
		)
		(fp_line
			(start 0.12065 0.2794)
			(end 0.12065 0.3048)
			(stroke
				(width 0.1)
				(type default)
			)
			(layer "B.Fab")
		)
		(fp_line
			(start 0.12065 -0.2794)
			(end -0.12065 -0.2794)
			(stroke
				(width 0.1)
				(type default)
			)
			(layer "B.Fab")
		)
		(fp_line
			(start 0.12065 -0.305054)
			(end 0.12065 -0.2794)
			(stroke
				(width 0.1)
				(type default)
			)
			(layer "B.Fab")
		)
		(fp_line
			(start -0.120396 0.3048)
			(end -0.120396 0.2794)
			(stroke
				(width 0.1)
				(type default)
			)
			(layer "B.Fab")
		)
		(fp_line
			(start -0.120396 0.2794)
			(end 0.12065 0.2794)
			(stroke
				(width 0.1)
				(type default)
			)
			(layer "B.Fab")
		)
		(fp_line
			(start -0.12065 -0.2794)
			(end -0.12065 -0.3048)
			(stroke
				(width 0.1)
				(type default)
			)
			(layer "B.Fab")
		)
		(fp_line
			(start -0.12065 -0.3048)
			(end -0.67945 -0.3048)
			(stroke
				(width 0.1)
				(type default)
			)
			(layer "B.Fab")
		)
		(fp_line
			(start -0.67945 0.3048)
			(end -0.120396 0.3048)
			(stroke
				(width 0.1)
				(type default)
			)
			(layer "B.Fab")
		)
		(fp_line
			(start -0.67945 -0.3048)
			(end -0.67945 0.3048)
			(stroke
				(width 0.1)
				(type default)
			)
			(layer "B.Fab")
		)
		(pad "1" smd circle
			(at 0.40005 0)
			(size 0 0)
			(layers "B.Cu" "B.Mask" "B.Paste")
			(net "P0V9_RETIMER_CPU0_TEMP0")
		)
		(pad "2" smd circle
			(at -0.40005 0)
			(size 0 0)
			(layers "B.Cu" "B.Mask" "B.Paste")
			(net "GND")
		)
	)
	(footprint ""
		(layer "B.Cu")
		(at 43.576748 -193.971164)
		(property "Reference" "C144"
			(at 0 0 0)
			(layer "B.SilkS")
			(hide yes)
			(effects
				(font
					(size 1.27 1.27)
				)
				(justify mirror)
			)
		)
		(property "Value" ""
			(at 0 0 0)
			(layer "B.Fab")
			(effects
				(font
					(size 1.27 1.27)
				)
				(justify mirror)
			)
		)
		(duplicate_pad_numbers_are_jumpers no)
		(fp_line
			(start -0.7874 -0.4064)
			(end -0.7874 0.4064)
			(stroke
				(width 0.1524)
				(type default)
			)
			(layer "B.SilkS")
		)
		(fp_line
			(start -0.7874 0.4064)
			(end 0.7874 0.4064)
			(stroke
				(width 0.1524)
				(type default)
			)
			(layer "B.SilkS")
		)
		(fp_line
			(start 0.7874 -0.4064)
			(end -0.7874 -0.4064)
			(stroke
				(width 0.1524)
				(type default)
			)
			(layer "B.SilkS")
		)
		(fp_line
			(start 0.7874 0.4064)
			(end 0.7874 -0.4064)
			(stroke
				(width 0.1524)
				(type default)
			)
			(layer "B.SilkS")
		)
		(fp_line
			(start -0.67945 -0.3048)
			(end -0.67945 0.3048)
			(stroke
				(width 0.1)
				(type default)
			)
			(layer "B.Fab")
		)
		(fp_line
			(start -0.67945 0.3048)
			(end -0.120396 0.3048)
			(stroke
				(width 0.1)
				(type default)
			)
			(layer "B.Fab")
		)
		(fp_line
			(start -0.12065 -0.3048)
			(end -0.67945 -0.3048)
			(stroke
				(width 0.1)
				(type default)
			)
			(layer "B.Fab")
		)
		(fp_line
			(start -0.12065 -0.2794)
			(end -0.12065 -0.3048)
			(stroke
				(width 0.1)
				(type default)
			)
			(layer "B.Fab")
		)
		(fp_line
			(start -0.120396 0.2794)
			(end 0.12065 0.2794)
			(stroke
				(width 0.1)
				(type default)
			)
			(layer "B.Fab")
		)
		(fp_line
			(start -0.120396 0.3048)
			(end -0.120396 0.2794)
			(stroke
				(width 0.1)
				(type default)
			)
			(layer "B.Fab")
		)
		(fp_line
			(start 0.12065 -0.305054)
			(end 0.12065 -0.2794)
			(stroke
				(width 0.1)
				(type default)
			)
			(layer "B.Fab")
		)
		(fp_line
			(start 0.12065 -0.2794)
			(end -0.12065 -0.2794)
			(stroke
				(width 0.1)
				(type default)
			)
			(layer "B.Fab")
		)
		(fp_line
			(start 0.12065 0.2794)
			(end 0.12065 0.3048)
			(stroke
				(width 0.1)
				(type default)
			)
			(layer "B.Fab")
		)
		(fp_line
			(start 0.12065 0.3048)
			(end 0.67945 0.3048)
			(stroke
				(width 0.1)
				(type default)
			)
			(layer "B.Fab")
		)
		(fp_line
			(start 0.67945 -0.305054)
			(end 0.12065 -0.305054)
			(stroke
				(width 0.1)
				(type default)
			)
			(layer "B.Fab")
		)
		(fp_line
			(start 0.67945 0.3048)
			(end 0.67945 -0.305054)
			(stroke
				(width 0.1)
				(type default)
			)
			(layer "B.Fab")
		)
		(pad "1" smd circle
			(at 0.40005 0 180)
			(size 0 0)
			(layers "B.Cu" "B.Mask" "B.Paste")
			(net "P3V3_AUX")
		)
		(pad "2" smd circle
			(at -0.40005 0 180)
			(size 0 0)
			(layers "B.Cu" "B.Mask" "B.Paste")
			(net "GND")
		)
	)
	(footprint ""
		(layer "B.Cu")
		(at 152.124918 -381.11303 180)
		(property "Reference" "C7027"
			(at -1.683004 -3.177032 0)
			(unlocked yes)
			(layer "B.SilkS")
			(effects
				(font
					(size 0.7874 0.5842)
					(thickness 0.1524)
				)
				(justify left mirror)
			)
		)
		(property "Value" ""
			(at 0 0 0)
			(layer "B.Fab")
			(effects
				(font
					(size 1.27 1.27)
				)
				(justify mirror)
			)
		)
		(duplicate_pad_numbers_are_jumpers no)
		(fp_line
			(start 4.84378 -2.150618)
			(end 4.842256 2.163064)
			(stroke
				(width 0.1524)
				(type default)
			)
			(layer "B.SilkS")
		)
		(fp_line
			(start 4.84378 -2.150618)
			(end 4.53898 -2.150618)
			(stroke
				(width 0.1524)
				(type default)
			)
			(layer "B.SilkS")
		)
		(fp_line
			(start 4.83108 2.150364)
			(end 4.447794 2.149348)
			(stroke
				(width 0.1524)
				(type default)
			)
			(layer "B.SilkS")
		)
		(fp_line
			(start 4.69138 -2.150618)
			(end 4.692396 2.161032)
			(stroke
				(width 0.1524)
				(type default)
			)
			(layer "B.SilkS")
		)
		(fp_line
			(start 4.53898 2.15011)
			(end 4.53898 -2.15011)
			(stroke
				(width 0.1524)
				(type default)
			)
			(layer "B.SilkS")
		)
		(fp_line
			(start 4.53898 -2.15011)
			(end -4.53898 -2.15011)
			(stroke
				(width 0.1524)
				(type default)
			)
			(layer "B.SilkS")
		)
		(fp_line
			(start 4.53898 -2.150618)
			(end 4.539742 2.152142)
			(stroke
				(width 0.1524)
				(type default)
			)
			(layer "B.SilkS")
		)
		(fp_line
			(start -4.53898 2.15011)
			(end 4.53898 2.15011)
			(stroke
				(width 0.1524)
				(type default)
			)
			(layer "B.SilkS")
		)
		(fp_line
			(start -4.53898 -2.15011)
			(end -4.53898 2.15011)
			(stroke
				(width 0.1524)
				(type default)
			)
			(layer "B.SilkS")
		)
		(fp_line
			(start 3.64998 2.15011)
			(end 3.64998 -2.15011)
			(stroke
				(width 0.1)
				(type default)
			)
			(layer "B.Fab")
		)
		(fp_line
			(start 3.64998 -2.15011)
			(end -3.64998 -2.15011)
			(stroke
				(width 0.1)
				(type default)
			)
			(layer "B.Fab")
		)
		(fp_line
			(start -3.64998 2.15011)
			(end 3.64998 2.15011)
			(stroke
				(width 0.1)
				(type default)
			)
			(layer "B.Fab")
		)
		(fp_line
			(start -3.64998 -2.15011)
			(end -3.64998 2.15011)
			(stroke
				(width 0.1)
				(type default)
			)
			(layer "B.Fab")
		)
		(fp_text user "+"
			(at 4.185412 -3.072638 180)
			(unlocked yes)
			(layer "B.SilkS")
			(effects
				(font
					(size 1.905 1.4224)
					(thickness 0.1524)
				)
				(justify left mirror)
			)
		)
		(fp_text user "-"
			(at -2.944114 -2.830068 180)
			(unlocked yes)
			(layer "B.SilkS")
			(effects
				(font
					(size 1.905 1.4224)
					(thickness 0.1524)
				)
				(justify left mirror)
			)
		)
		(fp_text user "+"
			(at 6.214872 -0.337058 180)
			(unlocked yes)
			(layer "B.Fab")
			(effects
				(font
					(size 1.905 1.4224)
					(thickness 0.1524)
				)
				(justify left mirror)
			)
		)
		(fp_text user "-"
			(at -4.313174 -0.094488 180)
			(unlocked yes)
			(layer "B.Fab")
			(effects
				(font
					(size 1.905 1.4224)
					(thickness 0.1524)
				)
				(justify left mirror)
			)
		)
		(pad "1" smd rect
			(at 3.199892 0)
			(size 2.413 2.8194)
			(layers "B.Cu" "B.Mask" "B.Paste")
			(net "P0V9_CPU1_RT2_2A")
		)
		(pad "2" smd rect
			(at -3.199892 0)
			(size 2.413 2.8194)
			(layers "B.Cu" "B.Mask" "B.Paste")
			(net "GND")
		)
	)
	(footprint ""
		(layer "B.Cu")
		(at 405.241252 -349.195644 -90)
		(property "Reference" "R6122"
			(at 0 0 90)
			(layer "B.SilkS")
			(hide yes)
			(effects
				(font
					(size 1.27 1.27)
				)
				(justify mirror)
			)
		)
		(property "Value" ""
			(at 0 0 90)
			(layer "B.Fab")
			(effects
				(font
					(size 1.27 1.27)
				)
				(justify mirror)
			)
		)
		(duplicate_pad_numbers_are_jumpers no)
		(fp_line
			(start -0.7874 0.4064)
			(end 0.7874 0.4064)
			(stroke
				(width 0.1524)
				(type default)
			)
			(layer "B.SilkS")
		)
		(fp_line
			(start 0.7874 0.4064)
			(end 0.7874 -0.4064)
			(stroke
				(width 0.1524)
				(type default)
			)
			(layer "B.SilkS")
		)
		(fp_line
			(start -0.7874 -0.4064)
			(end -0.7874 0.4064)
			(stroke
				(width 0.1524)
				(type default)
			)
			(layer "B.SilkS")
		)
		(fp_line
			(start 0.7874 -0.4064)
			(end -0.7874 -0.4064)
			(stroke
				(width 0.1524)
				(type default)
			)
			(layer "B.SilkS")
		)
		(fp_line
			(start -0.67945 0.3048)
			(end -0.120396 0.3048)
			(stroke
				(width 0.1)
				(type default)
			)
			(layer "B.Fab")
		)
		(fp_line
			(start -0.120396 0.3048)
			(end -0.120396 0.2794)
			(stroke
				(width 0.1)
				(type default)
			)
			(layer "B.Fab")
		)
		(fp_line
			(start 0.12065 0.3048)
			(end 0.67945 0.3048)
			(stroke
				(width 0.1)
				(type default)
			)
			(layer "B.Fab")
		)
		(fp_line
			(start 0.67945 0.3048)
			(end 0.67945 -0.305054)
			(stroke
				(width 0.1)
				(type default)
			)
			(layer "B.Fab")
		)
		(fp_line
			(start -0.120396 0.2794)
			(end 0.12065 0.2794)
			(stroke
				(width 0.1)
				(type default)
			)
			(layer "B.Fab")
		)
		(fp_line
			(start 0.12065 0.2794)
			(end 0.12065 0.3048)
			(stroke
				(width 0.1)
				(type default)
			)
			(layer "B.Fab")
		)
		(fp_line
			(start -0.12065 -0.2794)
			(end -0.12065 -0.3048)
			(stroke
				(width 0.1)
				(type default)
			)
			(layer "B.Fab")
		)
		(fp_line
			(start 0.12065 -0.2794)
			(end -0.12065 -0.2794)
			(stroke
				(width 0.1)
				(type default)
			)
			(layer "B.Fab")
		)
		(fp_line
			(start -0.67945 -0.3048)
			(end -0.67945 0.3048)
			(stroke
				(width 0.1)
				(type default)
			)
			(layer "B.Fab")
		)
		(fp_line
			(start -0.12065 -0.3048)
			(end -0.67945 -0.3048)
			(stroke
				(width 0.1)
				(type default)
			)
			(layer "B.Fab")
		)
		(fp_line
			(start 0.12065 -0.305054)
			(end 0.12065 -0.2794)
			(stroke
				(width 0.1)
				(type default)
			)
			(layer "B.Fab")
		)
		(fp_line
			(start 0.67945 -0.305054)
			(end 0.12065 -0.305054)
			(stroke
				(width 0.1)
				(type default)
			)
			(layer "B.Fab")
		)
		(pad "1" smd circle
			(at 0.40005 0 90)
			(size 0 0)
			(layers "B.Cu" "B.Mask" "B.Paste")
			(net "PVDD18_S5_P0")
		)
		(pad "2" smd circle
			(at -0.40005 0 90)
			(size 0 0)
			(layers "B.Cu" "B.Mask" "B.Paste")
			(net "FM_BOARD_SKU_ID2")
		)
	)
)
